(kicad_sch
	(version 20250114)
	(generator "eeschema")
	(generator_version "9.0")
	(paper "A3")
	(title_block
		(title "SDI-MIPI Video Converter")
		(date "2023-10-12")
		(rev "1.1.4")
		(comment 1 "www.antmicro.com")
		(comment 2 "Antmicro Ltd.")
	)
	(no_connect
		(at 325.12 226.06)
	)
	(no_connect
		(at 325.12 210.82)
	)
	(no_connect
		(at 325.12 203.2)
	)
	(no_connect
		(at 325.12 218.44)
	)
	(symbol
		(lib_id "antmicroMechanicalParts:MP_Pad5.4mm_Drill2.7mm")
		(at 325.12 218.44 0)
		(unit 1)
		(exclude_from_sim no)
		(in_bom no)
		(on_board yes)
		(dnp no)
		(fields_autoplaced yes)
		(property "Reference" "MP3"
			(at 334.01 217.17 0)
			(effects
				(font
					(size 1.27 1.27)
					(thickness 0.15)
				)
				(justify left)
			)
		)
		(property "Value" "MP_Pad5.4mm_Drill2.7mm"
			(at 334.01 219.71 0)
			(effects
				(font
					(size 1.27 1.27)
					(thickness 0.15)
				)
				(justify left)
			)
		)
		(property "Footprint" "antmicro-footprints:MP_Pad5.4mm_Drill2.7mm"
			(at 345.44 226.06 0)
			(effects
				(font
					(size 1.27 1.27)
					(thickness 0.15)
				)
				(justify left bottom)
				(hide yes)
			)
		)
		(property "Datasheet" ""
			(at 341.96 234.01 0)
			(effects
				(font
					(size 1.27 1.27)
					(thickness 0.15)
				)
				(justify left bottom)
				(hide yes)
			)
		)
		(property "Description" "Mechanical part"
			(at 345.44 233.68 0)
			(effects
				(font
					(size 1.27 1.27)
				)
				(justify left bottom)
				(hide yes)
			)
		)
		(property "Author" "Antmicro"
			(at 345.44 228.6 0)
			(effects
				(font
					(size 1.27 1.27)
					(thickness 0.15)
				)
				(justify left bottom)
				(hide yes)
			)
		)
		(property "License" "Apache-2.0"
			(at 345.44 231.14 0)
			(effects
				(font
					(size 1.27 1.27)
					(thickness 0.15)
				)
				(justify left bottom)
				(hide yes)
			)
		)
		(pin "1"
		)
		(instances
			(project "sdi-mipi-video-converter"
				(path ""
					(reference "MP3")
					(unit 1)
				)
			)
		)
	)
	(symbol
		(lib_id "antmicroMechanicalParts:MP_Pad5.4mm_Drill2.7mm")
		(at 325.12 203.2 0)
		(unit 1)
		(exclude_from_sim no)
		(in_bom no)
		(on_board yes)
		(dnp no)
		(fields_autoplaced yes)
		(property "Reference" "MP1"
			(at 334.01 201.93 0)
			(effects
				(font
					(size 1.27 1.27)
					(thickness 0.15)
				)
				(justify left)
			)
		)
		(property "Value" "MP_Pad5.4mm_Drill2.7mm"
			(at 334.01 204.47 0)
			(effects
				(font
					(size 1.27 1.27)
					(thickness 0.15)
				)
				(justify left)
			)
		)
		(property "Footprint" "antmicro-footprints:MP_Pad5.4mm_Drill2.7mm"
			(at 345.44 210.82 0)
			(effects
				(font
					(size 1.27 1.27)
					(thickness 0.15)
				)
				(justify left bottom)
				(hide yes)
			)
		)
		(property "Datasheet" ""
			(at 341.96 218.77 0)
			(effects
				(font
					(size 1.27 1.27)
					(thickness 0.15)
				)
				(justify left bottom)
				(hide yes)
			)
		)
		(property "Description" "Mechanical part"
			(at 345.44 218.44 0)
			(effects
				(font
					(size 1.27 1.27)
				)
				(justify left bottom)
				(hide yes)
			)
		)
		(property "Author" "Antmicro"
			(at 345.44 213.36 0)
			(effects
				(font
					(size 1.27 1.27)
					(thickness 0.15)
				)
				(justify left bottom)
				(hide yes)
			)
		)
		(property "License" "Apache-2.0"
			(at 345.44 215.9 0)
			(effects
				(font
					(size 1.27 1.27)
					(thickness 0.15)
				)
				(justify left bottom)
				(hide yes)
			)
		)
		(pin "1"
		)
		(instances
			(project ""
				(path ""
					(reference "MP1")
					(unit 1)
				)
			)
		)
	)
	(symbol
		(lib_id "antmicroMechanicalParts:MP_Pad5.4mm_Drill2.7mm")
		(at 325.12 210.82 0)
		(unit 1)
		(exclude_from_sim no)
		(in_bom no)
		(on_board yes)
		(dnp no)
		(fields_autoplaced yes)
		(property "Reference" "MP2"
			(at 334.01 209.55 0)
			(effects
				(font
					(size 1.27 1.27)
					(thickness 0.15)
				)
				(justify left)
			)
		)
		(property "Value" "MP_Pad5.4mm_Drill2.7mm"
			(at 334.01 212.09 0)
			(effects
				(font
					(size 1.27 1.27)
					(thickness 0.15)
				)
				(justify left)
			)
		)
		(property "Footprint" "antmicro-footprints:MP_Pad5.4mm_Drill2.7mm"
			(at 345.44 218.44 0)
			(effects
				(font
					(size 1.27 1.27)
					(thickness 0.15)
				)
				(justify left bottom)
				(hide yes)
			)
		)
		(property "Datasheet" ""
			(at 341.96 226.39 0)
			(effects
				(font
					(size 1.27 1.27)
					(thickness 0.15)
				)
				(justify left bottom)
				(hide yes)
			)
		)
		(property "Description" "Mechanical part"
			(at 345.44 226.06 0)
			(effects
				(font
					(size 1.27 1.27)
				)
				(justify left bottom)
				(hide yes)
			)
		)
		(property "Author" "Antmicro"
			(at 345.44 220.98 0)
			(effects
				(font
					(size 1.27 1.27)
					(thickness 0.15)
				)
				(justify left bottom)
				(hide yes)
			)
		)
		(property "License" "Apache-2.0"
			(at 345.44 223.52 0)
			(effects
				(font
					(size 1.27 1.27)
					(thickness 0.15)
				)
				(justify left bottom)
				(hide yes)
			)
		)
		(pin "1"
		)
		(instances
			(project "sdi-mipi-video-converter"
				(path ""
					(reference "MP2")
					(unit 1)
				)
			)
		)
	)
	(symbol
		(lib_id "antmicroMechanicalParts:MP_Pad5.4mm_Drill2.7mm")
		(at 325.12 226.06 0)
		(unit 1)
		(exclude_from_sim no)
		(in_bom no)
		(on_board yes)
		(dnp no)
		(fields_autoplaced yes)
		(property "Reference" "MP4"
			(at 334.01 224.79 0)
			(effects
				(font
					(size 1.27 1.27)
					(thickness 0.15)
				)
				(justify left)
			)
		)
		(property "Value" "MP_Pad5.4mm_Drill2.7mm"
			(at 334.01 227.33 0)
			(effects
				(font
					(size 1.27 1.27)
					(thickness 0.15)
				)
				(justify left)
			)
		)
		(property "Footprint" "antmicro-footprints:MP_Pad5.4mm_Drill2.7mm"
			(at 345.44 233.68 0)
			(effects
				(font
					(size 1.27 1.27)
					(thickness 0.15)
				)
				(justify left bottom)
				(hide yes)
			)
		)
		(property "Datasheet" ""
			(at 341.96 241.63 0)
			(effects
				(font
					(size 1.27 1.27)
					(thickness 0.15)
				)
				(justify left bottom)
				(hide yes)
			)
		)
		(property "Description" "Mechanical part"
			(at 345.44 241.3 0)
			(effects
				(font
					(size 1.27 1.27)
				)
				(justify left bottom)
				(hide yes)
			)
		)
		(property "Author" "Antmicro"
			(at 345.44 236.22 0)
			(effects
				(font
					(size 1.27 1.27)
					(thickness 0.15)
				)
				(justify left bottom)
				(hide yes)
			)
		)
		(property "License" "Apache-2.0"
			(at 345.44 238.76 0)
			(effects
				(font
					(size 1.27 1.27)
					(thickness 0.15)
				)
				(justify left bottom)
				(hide yes)
			)
		)
		(pin "1"
		)
		(instances
			(project "sdi-mipi-video-converter"
				(path ""
					(reference "MP4")
					(unit 1)
				)
			)
		)
	)
	(sheet
		(at 120.65 209.55)
		(size 22.86 13.97)
		(exclude_from_sim no)
		(in_bom yes)
		(on_board yes)
		(dnp no)
		(fields_autoplaced yes)
		(stroke
			(width 0.1524)
			(type solid)
		)
		(fill
			(color 0 0 0 0.0000)
		)
		(property "Sheetname" "SDI"
			(at 120.65 208.8384 0)
			(effects
				(font
					(size 1.27 1.27)
				)
				(justify left bottom)
			)
		)
		(property "Sheetfile" "sdi.kicad_sch"
			(at 120.65 224.1046 0)
			(effects
				(font
					(size 1.27 1.27)
				)
				(justify left top)
			)
		)
		(instances
			(project "sdi-mipi-video-converter"
				(path ""
					(page "5")
				)
			)
		)
	)
	(sheet
		(at 224.79 209.55)
		(size 20.32 13.97)
		(exclude_from_sim no)
		(in_bom yes)
		(on_board yes)
		(dnp no)
		(fields_autoplaced yes)
		(stroke
			(width 0.1524)
			(type solid)
		)
		(fill
			(color 0 0 0 0.0000)
		)
		(property "Sheetname" "Power Supply"
			(at 224.79 208.8384 0)
			(effects
				(font
					(size 1.27 1.27)
				)
				(justify left bottom)
			)
		)
		(property "Sheetfile" "supply.kicad_sch"
			(at 224.79 224.1046 0)
			(effects
				(font
					(size 1.27 1.27)
				)
				(justify left top)
			)
		)
		(instances
			(project "sdi-mipi-video-converter"
				(path ""
					(page "2")
				)
			)
		)
	)
	(sheet
		(at 153.67 209.55)
		(size 22.86 13.97)
		(exclude_from_sim no)
		(in_bom yes)
		(on_board yes)
		(dnp no)
		(fields_autoplaced yes)
		(stroke
			(width 0.1524)
			(type solid)
		)
		(fill
			(color 0 0 0 0.0000)
		)
		(property "Sheetname" "FPGA"
			(at 153.67 208.8384 0)
			(effects
				(font
					(size 1.27 1.27)
				)
				(justify left bottom)
			)
		)
		(property "Sheetfile" "fpga.kicad_sch"
			(at 153.67 224.1046 0)
			(effects
				(font
					(size 1.27 1.27)
				)
				(justify left top)
			)
		)
		(instances
			(project "sdi-mipi-video-converter"
				(path ""
					(page "6")
				)
			)
		)
	)
	(sheet
		(at 260.35 209.55)
		(size 21.59 13.97)
		(exclude_from_sim no)
		(in_bom yes)
		(on_board yes)
		(dnp no)
		(fields_autoplaced yes)
		(stroke
			(width 0.1524)
			(type solid)
		)
		(fill
			(color 0 0 0 0.0000)
		)
		(property "Sheetname" "DDR3"
			(at 260.35 208.8384 0)
			(effects
				(font
					(size 1.27 1.27)
				)
				(justify left bottom)
			)
		)
		(property "Sheetfile" "ddr3.kicad_sch"
			(at 260.35 224.1046 0)
			(effects
				(font
					(size 1.27 1.27)
				)
				(justify left top)
			)
		)
		(instances
			(project "sdi-mipi-video-converter"
				(path ""
					(page "3")
				)
			)
		)
	)
	(sheet
		(at 293.37 209.55)
		(size 21.59 13.97)
		(exclude_from_sim no)
		(in_bom yes)
		(on_board yes)
		(dnp no)
		(fields_autoplaced yes)
		(stroke
			(width 0.1524)
			(type solid)
		)
		(fill
			(color 0 0 0 0.0000)
		)
		(property "Sheetname" "Peripherals"
			(at 293.37 208.8384 0)
			(effects
				(font
					(size 1.27 1.27)
				)
				(justify left bottom)
			)
		)
		(property "Sheetfile" "peripherals.kicad_sch"
			(at 293.37 224.1046 0)
			(effects
				(font
					(size 1.27 1.27)
				)
				(justify left top)
			)
		)
		(instances
			(project "sdi-mipi-video-converter"
				(path ""
					(page "6")
				)
			)
		)
	)
	(sheet
		(at 186.69 209.55)
		(size 21.59 13.97)
		(exclude_from_sim no)
		(in_bom yes)
		(on_board yes)
		(dnp no)
		(fields_autoplaced yes)
		(stroke
			(width 0.1524)
			(type solid)
		)
		(fill
			(color 0 0 0 0.0000)
		)
		(property "Sheetname" "FPGA Power"
			(at 186.69 208.8384 0)
			(effects
				(font
					(size 1.27 1.27)
				)
				(justify left bottom)
			)
		)
		(property "Sheetfile" "FPGA_Power.kicad_sch"
			(at 186.69 224.1046 0)
			(effects
				(font
					(size 1.27 1.27)
				)
				(justify left top)
			)
		)
		(instances
			(project "sdi-mipi-video-converter"
				(path ""
					(page "7")
				)
			)
		)
	)
	(sheet_instances
		(path "/"
			(page "1")
		)
	)
)
